# SCM (Grand Teton) — schematic netlist excerpt (pin names and nets, part order shuffled) for the footprints in the layout excerpt that follows; sources: Cadence DE-HDL packaged netlist, KiCad conversion of 12092022_DA0F0TMDCD0_F0T_Management_Board_D_brd_V3_OCP.brd

C13  Q_CAP  0.1UF 25V 10% X7R  pkg 0402  page 20 : A = P1V2_AUX ; B = GND
C78  Q_CAP  1UF 25V 10% X6S  pkg C0402  page 17 : A = P1V0_STBY_PE_VCC10A ; B = GND

(kicad_pcb
	(version 20260206)
	(generator "pcbnew")
	(generator_version "10.0")
	(general
		(thickness 1.6)
		(legacy_teardrops no)
	)
	(paper "A4")
	(title_block
		(title "12092022_DA0F0TMDCD0_F0T_Management_Board_D_brd_V3_OCP.brd")
		(comment 1 "Grand Teton / footprints 1326-1327 of 1440")
	)
	(layers
		(0 "F.Cu" signal "TOP")
		(4 "In1.Cu" signal "GND")
		(6 "In2.Cu" signal "IN1")
		(8 "In3.Cu" signal "GND1")
		(10 "In4.Cu" signal "IN2")
		(12 "In5.Cu" signal "VCC")
		(14 "In6.Cu" signal "VCC1")
		(16 "In7.Cu" signal "IN3")
		(18 "In8.Cu" signal "GND2")
		(20 "In9.Cu" signal "IN4")
		(22 "In10.Cu" signal "GND3")
		(2 "B.Cu" signal "BOTTOM")
		(9 "F.Adhes" user "F.Adhesive")
		(11 "B.Adhes" user "B.Adhesive")
		(13 "F.Paste" user "Package Geometry/Pastemask Top")
		(15 "B.Paste" user "Package Geometry/Pastemask Bottom")
		(5 "F.SilkS" user "Ref Des/Silkscreen Top")
		(7 "B.SilkS" user "Ref Des/Silkscreen Bottom")
		(1 "F.Mask" user "Board Geometry/Soldermask Top")
		(3 "B.Mask" user "Board Geometry/Soldermask Bottom")
		(17 "Dwgs.User" user "User.Drawings")
		(19 "Cmts.User" user "User.Comments")
		(21 "Eco1.User" user "User.Eco1")
		(23 "Eco2.User" user "User.Eco2")
		(25 "Edge.Cuts" user "Board Geometry/Outline")
		(27 "Margin" user)
		(31 "F.CrtYd" user "Package Geometry/Place Bound Top")
		(29 "B.CrtYd" user "Package Geometry/Place Bound Bottom")
		(35 "F.Fab" user "Ref Des/Assembly Top")
		(33 "B.Fab" user "Ref Des/Assembly Bottom")
	)
	(footprint ""
		(layer "B.Cu")
		(at 72.029066 -60.839096 -90)
		(property "Reference" "C78"
			(at 0 0 90)
			(layer "B.SilkS")
			(hide yes)
			(effects
				(font
					(size 1.27 1.27)
				)
				(justify mirror)
			)
		)
		(property "Value" ""
			(at 0 0 90)
			(layer "B.Fab")
			(effects
				(font
					(size 1.27 1.27)
				)
				(justify mirror)
			)
		)
		(duplicate_pad_numbers_are_jumpers no)
		(fp_line
			(start -0.7874 0.4064)
			(end 0.7874 0.4064)
			(stroke
				(width 0.1524)
				(type default)
			)
			(layer "B.SilkS")
		)
		(fp_line
			(start 0.7874 0.4064)
			(end 0.7874 -0.4064)
			(stroke
				(width 0.1524)
				(type default)
			)
			(layer "B.SilkS")
		)
		(fp_line
			(start -0.7874 -0.4064)
			(end -0.7874 0.4064)
			(stroke
				(width 0.1524)
				(type default)
			)
			(layer "B.SilkS")
		)
		(fp_line
			(start 0.7874 -0.4064)
			(end -0.7874 -0.4064)
			(stroke
				(width 0.1524)
				(type default)
			)
			(layer "B.SilkS")
		)
		(fp_line
			(start -0.67945 0.3048)
			(end -0.120396 0.3048)
			(stroke
				(width 0.1)
				(type default)
			)
			(layer "B.Fab")
		)
		(fp_line
			(start -0.120396 0.3048)
			(end -0.120396 0.2794)
			(stroke
				(width 0.1)
				(type default)
			)
			(layer "B.Fab")
		)
		(fp_line
			(start 0.12065 0.3048)
			(end 0.67945 0.3048)
			(stroke
				(width 0.1)
				(type default)
			)
			(layer "B.Fab")
		)
		(fp_line
			(start 0.67945 0.3048)
			(end 0.67945 -0.305054)
			(stroke
				(width 0.1)
				(type default)
			)
			(layer "B.Fab")
		)
		(fp_line
			(start -0.120396 0.2794)
			(end 0.12065 0.2794)
			(stroke
				(width 0.1)
				(type default)
			)
			(layer "B.Fab")
		)
		(fp_line
			(start 0.12065 0.2794)
			(end 0.12065 0.3048)
			(stroke
				(width 0.1)
				(type default)
			)
			(layer "B.Fab")
		)
		(fp_line
			(start -0.12065 -0.2794)
			(end -0.12065 -0.3048)
			(stroke
				(width 0.1)
				(type default)
			)
			(layer "B.Fab")
		)
		(fp_line
			(start 0.12065 -0.2794)
			(end -0.12065 -0.2794)
			(stroke
				(width 0.1)
				(type default)
			)
			(layer "B.Fab")
		)
		(fp_line
			(start -0.67945 -0.3048)
			(end -0.67945 0.3048)
			(stroke
				(width 0.1)
				(type default)
			)
			(layer "B.Fab")
		)
		(fp_line
			(start -0.12065 -0.3048)
			(end -0.67945 -0.3048)
			(stroke
				(width 0.1)
				(type default)
			)
			(layer "B.Fab")
		)
		(fp_line
			(start 0.12065 -0.305054)
			(end 0.12065 -0.2794)
			(stroke
				(width 0.1)
				(type default)
			)
			(layer "B.Fab")
		)
		(fp_line
			(start 0.67945 -0.305054)
			(end 0.12065 -0.305054)
			(stroke
				(width 0.1)
				(type default)
			)
			(layer "B.Fab")
		)
		(pad "1" smd circle
			(at 0.40005 0 90)
			(size 0 0)
			(layers "B.Cu" "B.Mask" "B.Paste")
			(net "P1V0_STBY_PE_VCC10A")
		)
		(pad "2" smd circle
			(at -0.40005 0 90)
			(size 0 0)
			(layers "B.Cu" "B.Mask" "B.Paste")
			(net "GND")
		)
	)
	(footprint ""
		(layer "B.Cu")
		(at 85.29955 -47.488094)
		(property "Reference" "C13"
			(at 0 0 0)
			(layer "B.SilkS")
			(hide yes)
			(effects
				(font
					(size 1.27 1.27)
				)
				(justify mirror)
			)
		)
		(property "Value" ""
			(at 0 0 0)
			(layer "B.Fab")
			(effects
				(font
					(size 1.27 1.27)
				)
				(justify mirror)
			)
		)
		(duplicate_pad_numbers_are_jumpers no)
		(fp_line
			(start -0.7874 -0.4064)
			(end -0.7874 0.4064)
			(stroke
				(width 0.1524)
				(type default)
			)
			(layer "B.SilkS")
		)
		(fp_line
			(start -0.7874 0.4064)
			(end 0.7874 0.4064)
			(stroke
				(width 0.1524)
				(type default)
			)
			(layer "B.SilkS")
		)
		(fp_line
			(start 0.7874 -0.4064)
			(end -0.7874 -0.4064)
			(stroke
				(width 0.1524)
				(type default)
			)
			(layer "B.SilkS")
		)
		(fp_line
			(start 0.7874 0.4064)
			(end 0.7874 -0.4064)
			(stroke
				(width 0.1524)
				(type default)
			)
			(layer "B.SilkS")
		)
		(fp_line
			(start -0.67945 -0.3048)
			(end -0.67945 0.3048)
			(stroke
				(width 0.1)
				(type default)
			)
			(layer "B.Fab")
		)
		(fp_line
			(start -0.67945 0.3048)
			(end -0.120396 0.3048)
			(stroke
				(width 0.1)
				(type default)
			)
			(layer "B.Fab")
		)
		(fp_line
			(start -0.12065 -0.3048)
			(end -0.67945 -0.3048)
			(stroke
				(width 0.1)
				(type default)
			)
			(layer "B.Fab")
		)
		(fp_line
			(start -0.12065 -0.2794)
			(end -0.12065 -0.3048)
			(stroke
				(width 0.1)
				(type default)
			)
			(layer "B.Fab")
		)
		(fp_line
			(start -0.120396 0.2794)
			(end 0.12065 0.2794)
			(stroke
				(width 0.1)
				(type default)
			)
			(layer "B.Fab")
		)
		(fp_line
			(start -0.120396 0.3048)
			(end -0.120396 0.2794)
			(stroke
				(width 0.1)
				(type default)
			)
			(layer "B.Fab")
		)
		(fp_line
			(start 0.12065 -0.305054)
			(end 0.12065 -0.2794)
			(stroke
				(width 0.1)
				(type default)
			)
			(layer "B.Fab")
		)
		(fp_line
			(start 0.12065 -0.2794)
			(end -0.12065 -0.2794)
			(stroke
				(width 0.1)
				(type default)
			)
			(layer "B.Fab")
		)
		(fp_line
			(start 0.12065 0.2794)
			(end 0.12065 0.3048)
			(stroke
				(width 0.1)
				(type default)
			)
			(layer "B.Fab")
		)
		(fp_line
			(start 0.12065 0.3048)
			(end 0.67945 0.3048)
			(stroke
				(width 0.1)
				(type default)
			)
			(layer "B.Fab")
		)
		(fp_line
			(start 0.67945 -0.305054)
			(end 0.12065 -0.305054)
			(stroke
				(width 0.1)
				(type default)
			)
			(layer "B.Fab")
		)
		(fp_line
			(start 0.67945 0.3048)
			(end 0.67945 -0.305054)
			(stroke
				(width 0.1)
				(type default)
			)
			(layer "B.Fab")
		)
		(pad "1" smd circle
			(at 0.40005 0 180)
			(size 0 0)
			(layers "B.Cu" "B.Mask" "B.Paste")
			(net "P1V2_AUX")
		)
		(pad "2" smd circle
			(at -0.40005 0 180)
			(size 0 0)
			(layers "B.Cu" "B.Mask" "B.Paste")
			(net "GND")
		)
	)
)
